(kicad_pcb
	(version 20221018)
	(generator pcbnew)
	(general
    (thickness 1.518)
  )
	(paper "A4")
	(title_block
    (title "Kria K26 Devboard")
    (date "2024-03-26")
    (rev "1.2.5")
    (comment 1 "www.antmicro.com")
    (comment 2 "Antmicro Ltd.")
		(comment 9 "footprints 235-242 of 660")
	)
	(layers
    (0 "F.Cu" mixed)
    (1 "In1.Cu" power)
    (2 "In2.Cu" mixed)
    (3 "In3.Cu" power)
    (4 "In4.Cu" mixed)
    (5 "In5.Cu" power)
    (6 "In6.Cu" mixed)
    (31 "B.Cu" power)
    (32 "B.Adhes" user "B.Adhesive")
    (33 "F.Adhes" user "F.Adhesive")
    (34 "B.Paste" user)
    (35 "F.Paste" user)
    (36 "B.SilkS" user "B.Silkscreen")
    (37 "F.SilkS" user "F.Silkscreen")
    (38 "B.Mask" user)
    (39 "F.Mask" user)
    (40 "Dwgs.User" user "User.Drawings")
    (41 "Cmts.User" user "User.Comments")
    (42 "Eco1.User" user "User.Eco1")
    (43 "Eco2.User" user "User.Eco2")
    (44 "Edge.Cuts" user)
    (45 "Margin" user)
    (46 "B.CrtYd" user "B.Courtyard")
    (47 "F.CrtYd" user "F.Courtyard")
    (48 "B.Fab" user)
    (49 "F.Fab" user)
  )
	(footprint "kria-k26-devboard-footprints:R_0402_1005Metric" (layer "F.Cu")
    (at 129.28 117.32 -90)
    (descr "Resistor SMD 0402")
    (tags "resistor SMD 0402")
    (property "Author" "Antmicro")
    (property "Current" "1A")
    (property "License" "Apache-2.0")
    (property "MPN" "ERJ2GE0R00X")
    (property "Manufacturer" "Panasonic")
    (property "Sheetfile" "pcie-m2-key-e.kicad_sch")
    (property "Sheetname" "PCIE M2 key E ")
    (property "Tolerance" "")
    (property "Val" "0R")
    (property "ki_description" "0R resistor in 0402 package with unspecified tolerance")
    (attr smd)
    (fp_text reference "R150" (at 1.45 -1.24 -90) (layer "F.SilkS")
        (effects (font (size 0.7 0.7) (thickness 0.15)) (justify left bottom))
    )
    (fp_text value "R_0R_0402" (at 0 1.4 -90) (layer "F.Fab") hide
        (effects (font (size 0.7 0.7) (thickness 0.15)) (justify left bottom))
    )
    (fp_text user "Author: Antmicro" (at -0.95 4.169 -90) (layer "F.Fab") hide
        (effects (font (size 0.7 0.7) (thickness 0.15)) (justify left bottom))
    )
    (fp_text user "${REFERENCE}" (at -0.95 3.168 -90) (layer "F.Fab") hide
        (effects (font (size 0.7 0.7) (thickness 0.15)) (justify left bottom))
    )
    (fp_text user "License: Apache-2.0" (at -0.95 5.169 -90) (layer "F.Fab") hide
        (effects (font (size 0.7 0.7) (thickness 0.15)) (justify left bottom))
    )
    (fp_rect (start -0.93 -0.47) (end 0.93 0.47)
      (stroke (width 0.05) (type solid)) (fill none) (layer "F.CrtYd"))
    (fp_rect (start -0.5 -0.25) (end 0.5 0.25)
      (stroke (width 0.15) (type solid)) (fill none) (layer "F.Fab"))
    (pad "1" smd roundrect (at -0.485 0 270) (size 0.59 0.64) (layers "F.Cu" "F.Paste" "F.Mask") (roundrect_rratio 0.25)
      (net 226 "/Clock distribution/~{M2_CLKREQ}") (pintype "passive"))
    (pad "2" smd roundrect (at 0.485 0 270) (size 0.59 0.64) (layers "F.Cu" "F.Paste" "F.Mask") (roundrect_rratio 0.25)
      (net 396 "Net-(J12-~{CLKREQ0})") (pintype "passive"))
  )
	(footprint "kria-k26-devboard-footprints:C_0402_1005Metric" (layer "F.Cu")
    (at 168.5 132.2 180)
    (descr "Capacitor SMD 0402")
    (tags "capacitor SMD 0402")
    (property "Author" "Antmicro")
    (property "Dielectric" "X5R")
    (property "License" "Apache-2.0")
    (property "MPN" "GRM155R61H104KE14D")
    (property "Manufacturer" "Murata")
    (property "Sheetfile" "dc-dc-conventers.kicad_sch")
    (property "Sheetname" "DC/DC conventers")
    (property "Val" "100n")
    (property "Voltage" "50V")
    (property "ki_description" " ")
    (attr smd)
    (fp_text reference "C206" (at 3.68 -0.4 180) (layer "F.SilkS")
        (effects (font (size 0.7 0.7) (thickness 0.15)) (justify left bottom))
    )
    (fp_text value "C_100n_0402" (at 0 1.4 180) (layer "F.Fab") hide
        (effects (font (size 0.7 0.7) (thickness 0.15)) (justify left bottom))
    )
    (fp_text user "Author: Antmicro" (at -0.932 4.17 180) (layer "F.Fab") hide
        (effects (font (size 0.7 0.7) (thickness 0.15)) (justify left bottom))
    )
    (fp_text user "${REFERENCE}" (at -0.932 3.168 180) (layer "F.Fab") hide
        (effects (font (size 0.7 0.7) (thickness 0.15)) (justify left bottom))
    )
    (fp_text user "License: Apache-2.0" (at -0.932 5.17 180) (layer "F.Fab") hide
        (effects (font (size 0.7 0.7) (thickness 0.15)) (justify left bottom))
    )
    (fp_rect (start -0.94 -0.47) (end 0.94 0.47)
      (stroke (width 0.05) (type solid)) (fill none) (layer "F.CrtYd"))
    (fp_rect (start -0.499 -0.249) (end 0.499 0.249)
      (stroke (width 0.15) (type solid)) (fill none) (layer "F.Fab"))
    (pad "1" smd roundrect (at -0.484 0 180) (size 0.59 0.64) (layers "F.Cu" "F.Paste" "F.Mask") (roundrect_rratio 0.25)
      (net 257 "Net-(U49-BST)") (pintype "passive"))
    (pad "2" smd roundrect (at 0.484 0 180) (size 0.59 0.64) (layers "F.Cu" "F.Paste" "F.Mask") (roundrect_rratio 0.25)
      (net 309 "/Power Supply/DC/DC conventers/SW_PS_3V3") (pintype "passive"))
  )
	(footprint "kria-k26-devboard-footprints:SOT-416" (layer "F.Cu")
    (at 173.65 116.35 90)
    (descr "SOT-416")
    (tags "SOT-416")
    (property "Author" "Antmicro")
    (property "License" "Apache-2.0")
    (property "MPN" "DTC014TEBTL")
    (property "Manufacturer" "ROHM Semiconductor")
    (property "Sheetfile" "dc-dc-conventers.kicad_sch")
    (property "Sheetname" "DC/DC conventers")
    (property "ki_description" "Digital NPN Transistor, 10k/NONE, EMT-3")
    (attr smd)
    (fp_text reference "Q13" (at 1.13 -0.84 180) (layer "F.SilkS")
        (effects (font (size 0.7 0.7) (thickness 0.15)) (justify left bottom))
    )
    (fp_text value "DTC014T_SOT-416" (at 0 2 90) (layer "F.Fab") hide
        (effects (font (size 0.7 0.7) (thickness 0.15)) (justify left bottom))
    )
    (fp_text user "Author: Antmicro" (at -1 4.602 90) (layer "F.Fab") hide
        (effects (font (size 0.7 0.7) (thickness 0.15)) (justify left bottom))
    )
    (fp_text user "License: Apache-2.0" (at -1 5.802 90) (layer "F.Fab") hide
        (effects (font (size 0.7 0.7) (thickness 0.15)) (justify left bottom))
    )
    (fp_text user "${REFERENCE}" (at -1 3.4 90) (layer "F.Fab") hide
        (effects (font (size 0.7 0.7) (thickness 0.15)) (justify left bottom))
    )
    (fp_line (start -0.5 -0.15) (end -0.5 0.15)
      (stroke (width 0.15) (type solid)) (layer "F.SilkS"))
    (fp_line (start 0.5 0.9) (end -0.5 0.9)
      (stroke (width 0.15) (type solid)) (layer "F.SilkS"))
    (fp_line (start 0.5 0.9) (end 0.5 0.7)
      (stroke (width 0.15) (type solid)) (layer "F.SilkS"))
    (fp_line (start 0.508 -0.9) (end -0.5 -0.9)
      (stroke (width 0.15) (type solid)) (layer "F.SilkS"))
    (fp_line (start 0.508 -0.9) (end 0.508 -0.592)
      (stroke (width 0.15) (type solid)) (layer "F.SilkS"))
    (fp_rect (start -1 -1.05) (end 1 1.05)
      (stroke (width 0.05) (type solid)) (fill none) (layer "F.CrtYd"))
    (fp_line (start -0.05 -0.9) (end -0.45 -0.5)
      (stroke (width 0.15) (type solid)) (layer "F.Fab"))
    (fp_rect (start 0.45 0.9) (end -0.45 -0.9)
      (stroke (width 0.15) (type solid)) (fill none) (layer "F.Fab"))
    (pad "1" smd rect (at -0.652 -0.5 90) (size 0.6 0.5) (layers "F.Cu" "F.Paste" "F.Mask")
      (net 768 "/Power Supply/DC/DC conventers/PS_1V2_OUT") (pinfunction "B") (pintype "input"))
    (pad "2" smd rect (at -0.652 0.498 90) (size 0.6 0.5) (layers "F.Cu" "F.Paste" "F.Mask")
      (net 1 "GND") (pinfunction "E") (pintype "passive"))
    (pad "3" smd rect (at 0.65 0 90) (size 0.6 0.5) (layers "F.Cu" "F.Paste" "F.Mask")
      (net 338 "Net-(Q13-C)") (pinfunction "C") (pintype "passive"))
  )
	(footprint "kria-k26-devboard-footprints:LED_0603_1608Metric_G" (layer "F.Cu")
    (at 171.1 115.425)
    (descr "LED SMD 0603 Green")
    (tags "LED SMD 0603 Green")
    (property "Author" "Antmicro")
    (property "Color" "Green")
    (property "License" "Apache-2.0")
    (property "MPN" "LG L29K-G2J1-24-Z")
    (property "Manufacturer" "OSRAM")
    (property "Sheetfile" "dc-dc-conventers.kicad_sch")
    (property "Sheetname" "DC/DC conventers")
    (property "ki_description" "LED, Green, SMT, 0603, 20 mA, 2.1 V, 570 nm")
    (property "ki_keywords" "0603, SMT, DIODE, SEMICONDUCTOR, UNICOLOR")
    (attr smd)
    (fp_text reference "D17" (at 1.43 -1.025) (layer "F.SilkS")
        (effects (font (size 0.7 0.7) (thickness 0.15)) (justify left bottom))
    )
    (fp_text value "LED_G_0603_LG_L29K-G2J1-24-Z" (at 0 1.6) (layer "F.Fab") hide
        (effects (font (size 0.7 0.7) (thickness 0.15)) (justify left bottom))
    )
    (fp_text user "${REFERENCE}" (at -1.31 3.769) (layer "F.Fab") hide
        (effects (font (size 0.7 0.7) (thickness 0.15)) (justify left bottom))
    )
    (fp_text user "License: Apache-2.0" (at -1.31 5.769) (layer "F.Fab") hide
        (effects (font (size 0.7 0.7) (thickness 0.15)) (justify left bottom))
    )
    (fp_text user "Author: Antmicro" (at -1.31 4.769) (layer "F.Fab") hide
        (effects (font (size 0.7 0.7) (thickness 0.15)) (justify left bottom))
    )
    (fp_line (start -0.27 -0.35) (end 0.27 -0.35)
      (stroke (width 0.15) (type solid)) (layer "F.SilkS"))
    (fp_line (start -0.27 0.351) (end 0.27 0.351)
      (stroke (width 0.15) (type solid)) (layer "F.SilkS"))
    (fp_line (start -0.106328 -0.200008) (end -0.106328 0.199992)
      (stroke (width 0.1) (type solid)) (layer "F.SilkS"))
    (fp_line (start -0.106328 -0.200008) (end 0.093672 -0.000008)
      (stroke (width 0.1) (type solid)) (layer "F.SilkS"))
    (fp_line (start -0.106328 -0.000008) (end -0.29 0)
      (stroke (width 0.1) (type solid)) (layer "F.SilkS"))
    (fp_line (start 0.093672 -0.200008) (end 0.093672 0.199992)
      (stroke (width 0.1) (type solid)) (layer "F.SilkS"))
    (fp_line (start 0.093672 -0.000008) (end -0.106328 0.199992)
      (stroke (width 0.1) (type solid)) (layer "F.SilkS"))
    (fp_line (start 0.093672 -0.000008) (end 0.293672 -0.000008)
      (stroke (width 0.1) (type solid)) (layer "F.SilkS"))
    (fp_line (start 1.25 0.32) (end 1.25 -0.32)
      (stroke (width 0.15) (type solid)) (layer "F.SilkS"))
    (fp_rect (start 1.26 0.65) (end -1.26 -0.65)
      (stroke (width 0.05) (type solid)) (fill none) (layer "F.CrtYd"))
    (fp_line (start -0.599 0) (end -0.201 0)
      (stroke (width 0.15) (type solid)) (layer "F.Fab"))
    (fp_line (start -0.201 -0.2) (end -0.201 0)
      (stroke (width 0.15) (type solid)) (layer "F.Fab"))
    (fp_line (start -0.201 0) (end -0.201 0.202)
      (stroke (width 0.15) (type solid)) (layer "F.Fab"))
    (fp_line (start -0.201 0.202) (end 0.101 0)
      (stroke (width 0.15) (type solid)) (layer "F.Fab"))
    (fp_line (start 0.101 0) (end -0.201 -0.2)
      (stroke (width 0.15) (type solid)) (layer "F.Fab"))
    (fp_line (start 0.199 -0.2) (end 0.199 -0.1)
      (stroke (width 0.15) (type solid)) (layer "F.Fab"))
    (fp_line (start 0.199 0) (end 0.597 0)
      (stroke (width 0.15) (type solid)) (layer "F.Fab"))
    (fp_line (start 0.199 0.202) (end 0.199 -0.1)
      (stroke (width 0.15) (type solid)) (layer "F.Fab"))
    (fp_rect (start -0.848 -0.4) (end 0.85 0.402)
      (stroke (width 0.15) (type solid)) (fill none) (layer "F.Fab"))
    (pad "1" smd rect (at -0.75 0 180) (size 0.8 0.8) (layers "F.Cu" "F.Paste" "F.Mask")
      (net 242 "Net-(D17-Pad1)") (pintype "passive"))
    (pad "2" smd rect (at 0.75 0 180) (size 0.8 0.8) (layers "F.Cu" "F.Paste" "F.Mask")
      (net 338 "Net-(Q13-C)") (pinfunction "2") (pintype "passive"))
  )
	(footprint "kria-k26-devboard-footprints:R_0402_1005Metric" (layer "F.Cu")
    (at 168.75 115.675)
    (descr "Resistor SMD 0402")
    (tags "resistor SMD 0402")
    (property "Author" "Antmicro")
    (property "License" "Apache-2.0")
    (property "MPN" "CR0402-FX-1001GLF")
    (property "Manufacturer" "Bourns")
    (property "Sheetfile" "dc-dc-conventers.kicad_sch")
    (property "Sheetname" "DC/DC conventers")
    (property "Tolerance" "1%")
    (property "Val" "1k")
    (property "ki_description" "1k resistor in 0402 package with 1% tolerance")
    (attr smd)
    (fp_text reference "R130" (at -3.26 -1.055) (layer "F.SilkS")
        (effects (font (size 0.7 0.7) (thickness 0.15)) (justify left bottom))
    )
    (fp_text value "R_1k_0402" (at 0 1.4) (layer "F.Fab") hide
        (effects (font (size 0.7 0.7) (thickness 0.15)) (justify left bottom))
    )
    (fp_text user "Author: Antmicro" (at -0.95 4.169) (layer "F.Fab") hide
        (effects (font (size 0.7 0.7) (thickness 0.15)) (justify left bottom))
    )
    (fp_text user "${REFERENCE}" (at -0.95 3.168) (layer "F.Fab") hide
        (effects (font (size 0.7 0.7) (thickness 0.15)) (justify left bottom))
    )
    (fp_text user "License: Apache-2.0" (at -0.95 5.169) (layer "F.Fab") hide
        (effects (font (size 0.7 0.7) (thickness 0.15)) (justify left bottom))
    )
    (fp_rect (start -0.93 -0.47) (end 0.93 0.47)
      (stroke (width 0.05) (type solid)) (fill none) (layer "F.CrtYd"))
    (fp_rect (start -0.5 -0.25) (end 0.5 0.25)
      (stroke (width 0.15) (type solid)) (fill none) (layer "F.Fab"))
    (pad "1" smd roundrect (at -0.485 0) (size 0.59 0.64) (layers "F.Cu" "F.Paste" "F.Mask") (roundrect_rratio 0.25)
      (net 765 "/Power Supply/DC/DC conventers/PS_3V3_OUT") (pintype "passive"))
    (pad "2" smd roundrect (at 0.485 0) (size 0.59 0.64) (layers "F.Cu" "F.Paste" "F.Mask") (roundrect_rratio 0.25)
      (net 242 "Net-(D17-Pad1)") (pintype "passive"))
  )
	(footprint "kria-k26-devboard-footprints:L_0806_2016Metric" (layer "F.Cu")
    (at 169.646999 117.3 180)
    (property "Author" "Antmicro")
    (property "IMax" "")
    (property "ISat" "")
    (property "License" "Apache-2.0")
    (property "MPN" "SRP2010-1R0M")
    (property "Manufacturer" "Bourns")
    (property "Sheetfile" "dc-dc-conventers.kicad_sch")
    (property "Sheetname" "DC/DC conventers")
    (property "Size" "2.0x1.6")
    (property "Val" "1u/2.6A")
    (attr smd)
    (fp_text reference "L6" (at -2.183001 -1.98 180) (layer "F.SilkS")
        (effects (font (size 0.7 0.7) (thickness 0.15)) (justify left bottom))
    )
    (fp_text value "L_1u_2.6A_0806" (at 0 2 180) (layer "F.Fab") hide
        (effects (font (size 0.7 0.7) (thickness 0.15)) (justify left bottom))
    )
    (fp_text user "Author: Antmicro" (at -1.9 4.4 180) (layer "F.Fab") hide
        (effects (font (size 0.7 0.7) (thickness 0.15)) (justify left bottom))
    )
    (fp_text user "${REFERENCE}" (at -1.9 3.1 180) (layer "F.Fab") hide
        (effects (font (size 0.7 0.7) (thickness 0.15)) (justify left bottom))
    )
    (fp_text user "License: Apache-2.0" (at -1.9 5.75 180) (layer "F.Fab") hide
        (effects (font (size 0.7 0.7) (thickness 0.15)) (justify left bottom))
    )
    (fp_line (start -0.301 0.9) (end 0.299 0.9)
      (stroke (width 0.15) (type solid)) (layer "F.SilkS"))
    (fp_line (start -0.3 -0.9) (end 0.298 -0.9)
      (stroke (width 0.15) (type solid)) (layer "F.SilkS"))
    (fp_rect (start -1.75 -1.05) (end 1.75 1.05)
      (stroke (width 0.05) (type solid)) (fill none) (layer "F.CrtYd"))
    (fp_rect (start -0.951 -0.882) (end 0.949 0.875)
      (stroke (width 0.15) (type solid)) (fill none) (layer "F.Fab"))
    (pad "1" smd roundrect (at -1.1 -0.001 180) (size 1 1.8) (layers "F.Cu" "F.Paste" "F.Mask") (roundrect_rratio 0.15)
      (net 312 "/Power Supply/DC/DC conventers/SW_PS_1V2") (pintype "passive"))
    (pad "2" smd roundrect (at 1.1 -0.001 180) (size 1 1.8) (layers "F.Cu" "F.Paste" "F.Mask") (roundrect_rratio 0.15)
      (net 768 "/Power Supply/DC/DC conventers/PS_1V2_OUT") (pintype "passive"))
  )
	(footprint "kria-k26-devboard-footprints:R_0402_1005Metric" (layer "F.Cu")
    (at 174.125 120.95)
    (descr "Resistor SMD 0402")
    (tags "resistor SMD 0402")
    (property "Author" "Antmicro")
    (property "License" "Apache-2.0")
    (property "MPN" "CR0402-FX-1002GLF")
    (property "Manufacturer" "Bourns")
    (property "Sheetfile" "dc-dc-conventers.kicad_sch")
    (property "Sheetname" "DC/DC conventers")
    (property "Tolerance" "1%")
    (property "Val" "10k")
    (property "ki_description" "10k resistor in 0402 package with 1% tolerance")
    (attr smd)
    (fp_text reference "R138" (at -0.755 1.19) (layer "F.SilkS")
        (effects (font (size 0.7 0.7) (thickness 0.15)) (justify left bottom))
    )
    (fp_text value "R_10k_0402" (at 0 1.4) (layer "F.Fab") hide
        (effects (font (size 0.7 0.7) (thickness 0.15)) (justify left bottom))
    )
    (fp_text user "Author: Antmicro" (at -0.95 4.169) (layer "F.Fab") hide
        (effects (font (size 0.7 0.7) (thickness 0.15)) (justify left bottom))
    )
    (fp_text user "${REFERENCE}" (at -0.95 3.168) (layer "F.Fab") hide
        (effects (font (size 0.7 0.7) (thickness 0.15)) (justify left bottom))
    )
    (fp_text user "License: Apache-2.0" (at -0.95 5.169) (layer "F.Fab") hide
        (effects (font (size 0.7 0.7) (thickness 0.15)) (justify left bottom))
    )
    (fp_rect (start -0.93 -0.47) (end 0.93 0.47)
      (stroke (width 0.05) (type solid)) (fill none) (layer "F.CrtYd"))
    (fp_rect (start -0.5 -0.25) (end 0.5 0.25)
      (stroke (width 0.15) (type solid)) (fill none) (layer "F.Fab"))
    (pad "1" smd roundrect (at -0.485 0) (size 0.59 0.64) (layers "F.Cu" "F.Paste" "F.Mask") (roundrect_rratio 0.25)
      (net 691 "Net-(U52-FB)") (pintype "passive"))
    (pad "2" smd roundrect (at 0.485 0) (size 0.59 0.64) (layers "F.Cu" "F.Paste" "F.Mask") (roundrect_rratio 0.25)
      (net 1 "GND") (pintype "passive"))
  )
	(footprint "kria-k26-devboard-footprints:R_0402_1005Metric" (layer "F.Cu")
    (at 172.7 120.48 -90)
    (descr "Resistor SMD 0402")
    (tags "resistor SMD 0402")
    (property "Author" "Antmicro")
    (property "License" "Apache-2.0")
    (property "MPN" "CR0402-FX-4991GLF")
    (property "Manufacturer" "Bourns")
    (property "Sheetfile" "dc-dc-conventers.kicad_sch")
    (property "Sheetname" "DC/DC conventers")
    (property "Tolerance" "1%")
    (property "Val" "4k99")
    (property "ki_description" "4k99 resistor in 0402 package with 1% tolerance")
    (attr smd)
    (fp_text reference "R137" (at -0.43 -0.31) (layer "F.SilkS")
        (effects (font (size 0.7 0.7) (thickness 0.15)) (justify left bottom))
    )
    (fp_text value "R_4k99_0402" (at 0 1.4 -90) (layer "F.Fab") hide
        (effects (font (size 0.7 0.7) (thickness 0.15)) (justify left bottom))
    )
    (fp_text user "${REFERENCE}" (at -0.95 3.168 -90) (layer "F.Fab") hide
        (effects (font (size 0.7 0.7) (thickness 0.15)) (justify left bottom))
    )
    (fp_text user "Author: Antmicro" (at -0.95 4.169 -90) (layer "F.Fab") hide
        (effects (font (size 0.7 0.7) (thickness 0.15)) (justify left bottom))
    )
    (fp_text user "License: Apache-2.0" (at -0.95 5.169 -90) (layer "F.Fab") hide
        (effects (font (size 0.7 0.7) (thickness 0.15)) (justify left bottom))
    )
    (fp_rect (start -0.93 -0.47) (end 0.93 0.47)
      (stroke (width 0.05) (type solid)) (fill none) (layer "F.CrtYd"))
    (fp_rect (start -0.5 -0.25) (end 0.5 0.25)
      (stroke (width 0.15) (type solid)) (fill none) (layer "F.Fab"))
    (pad "1" smd roundrect (at -0.485 0 270) (size 0.59 0.64) (layers "F.Cu" "F.Paste" "F.Mask") (roundrect_rratio 0.25)
      (net 768 "/Power Supply/DC/DC conventers/PS_1V2_OUT") (pintype "passive"))
    (pad "2" smd roundrect (at 0.485 0 270) (size 0.59 0.64) (layers "F.Cu" "F.Paste" "F.Mask") (roundrect_rratio 0.25)
      (net 691 "Net-(U52-FB)") (pintype "passive"))
  )
)
